(kicad_pcb
	(version 20260206)
	(generator "pcbnew")
	(generator_version "10.0")
	(general
		(thickness 1.6)
		(legacy_teardrops no)
	)
	(paper "A4")
	(title_block
		(title "01162023_DA0F0TEBIF0_F0T_Expander_BD_F_brd_V02_OCP.brd")
		(comment 1 "Grand Teton / footprints 131-136 of 9728")
	)
	(layers
		(0 "F.Cu" signal "TOP")
		(4 "In1.Cu" signal "GND")
		(6 "In2.Cu" signal "VCC")
		(8 "In3.Cu" signal "VCC1")
		(10 "In4.Cu" signal "GND1")
		(12 "In5.Cu" signal "IN1")
		(14 "In6.Cu" signal "GND2")
		(16 "In7.Cu" signal "IN2")
		(18 "In8.Cu" signal "GND3")
		(20 "In9.Cu" signal "IN3")
		(22 "In10.Cu" signal "GND4")
		(24 "In11.Cu" signal "IN4")
		(26 "In12.Cu" signal "GND5")
		(28 "In13.Cu" signal "IN5")
		(30 "In14.Cu" signal "GND6")
		(32 "In15.Cu" signal "IN6")
		(34 "In16.Cu" signal "GND7")
		(2 "B.Cu" signal "BOTTOM")
		(9 "F.Adhes" user "F.Adhesive")
		(11 "B.Adhes" user "B.Adhesive")
		(13 "F.Paste" user "Package Geometry/Pastemask Top")
		(15 "B.Paste" user "Package Geometry/Pastemask Bottom")
		(5 "F.SilkS" user "Ref Des/Silkscreen Top")
		(7 "B.SilkS" user "Ref Des/Silkscreen Bottom")
		(1 "F.Mask" user "Board Geometry/Soldermask Top")
		(3 "B.Mask" user "Board Geometry/Soldermask Bottom")
		(17 "Dwgs.User" user "User.Drawings")
		(19 "Cmts.User" user "User.Comments")
		(21 "Eco1.User" user "User.Eco1")
		(23 "Eco2.User" user "User.Eco2")
		(25 "Edge.Cuts" user "Board Geometry/Outline")
		(27 "Margin" user)
		(31 "F.CrtYd" user "Package Geometry/Place Bound Top")
		(29 "B.CrtYd" user "Package Geometry/Place Bound Bottom")
		(35 "F.Fab" user "Ref Des/Assembly Top")
		(33 "B.Fab" user "Ref Des/Assembly Bottom")
	)
	(footprint ""
		(layer "F.Cu")
		(at 210.439 -202.819 180)
		(property "Reference" "R1518"
			(at 0 0 180)
			(layer "F.SilkS")
			(hide yes)
			(effects
				(font
					(size 1.27 1.27)
				)
			)
		)
		(property "Value" ""
			(at 0 0 180)
			(layer "F.Fab")
			(effects
				(font
					(size 1.27 1.27)
				)
			)
		)
		(duplicate_pad_numbers_are_jumpers no)
		(fp_line
			(start 0.7874 0.4064)
			(end -0.7874 0.4064)
			(stroke
				(width 0.1524)
				(type default)
			)
			(layer "F.SilkS")
		)
		(fp_line
			(start 0.7874 -0.4064)
			(end 0.7874 0.4064)
			(stroke
				(width 0.1524)
				(type default)
			)
			(layer "F.SilkS")
		)
		(fp_line
			(start -0.7874 0.4064)
			(end -0.7874 -0.4064)
			(stroke
				(width 0.1524)
				(type default)
			)
			(layer "F.SilkS")
		)
		(fp_line
			(start -0.7874 -0.4064)
			(end 0.7874 -0.4064)
			(stroke
				(width 0.1524)
				(type default)
			)
			(layer "F.SilkS")
		)
		(fp_line
			(start 0.67945 0.3048)
			(end 0.120396 0.3048)
			(stroke
				(width 0.1)
				(type default)
			)
			(layer "F.Fab")
		)
		(fp_line
			(start 0.67945 -0.3048)
			(end 0.67945 0.3048)
			(stroke
				(width 0.1)
				(type default)
			)
			(layer "F.Fab")
		)
		(fp_line
			(start 0.12065 -0.2794)
			(end 0.12065 -0.3048)
			(stroke
				(width 0.1)
				(type default)
			)
			(layer "F.Fab")
		)
		(fp_line
			(start 0.12065 -0.3048)
			(end 0.67945 -0.3048)
			(stroke
				(width 0.1)
				(type default)
			)
			(layer "F.Fab")
		)
		(fp_line
			(start 0.120396 0.3048)
			(end 0.120396 0.2794)
			(stroke
				(width 0.1)
				(type default)
			)
			(layer "F.Fab")
		)
		(fp_line
			(start 0.120396 0.2794)
			(end -0.12065 0.2794)
			(stroke
				(width 0.1)
				(type default)
			)
			(layer "F.Fab")
		)
		(fp_line
			(start -0.12065 0.3048)
			(end -0.67945 0.3048)
			(stroke
				(width 0.1)
				(type default)
			)
			(layer "F.Fab")
		)
		(fp_line
			(start -0.12065 0.2794)
			(end -0.12065 0.3048)
			(stroke
				(width 0.1)
				(type default)
			)
			(layer "F.Fab")
		)
		(fp_line
			(start -0.12065 -0.2794)
			(end 0.12065 -0.2794)
			(stroke
				(width 0.1)
				(type default)
			)
			(layer "F.Fab")
		)
		(fp_line
			(start -0.12065 -0.305054)
			(end -0.12065 -0.2794)
			(stroke
				(width 0.1)
				(type default)
			)
			(layer "F.Fab")
		)
		(fp_line
			(start -0.67945 0.3048)
			(end -0.67945 -0.305054)
			(stroke
				(width 0.1)
				(type default)
			)
			(layer "F.Fab")
		)
		(fp_line
			(start -0.67945 -0.305054)
			(end -0.12065 -0.305054)
			(stroke
				(width 0.1)
				(type default)
			)
			(layer "F.Fab")
		)
		(pad "1" smd circle
			(at -0.40005 0 180)
			(size 0 0)
			(layers "F.Cu" "F.Mask" "F.Paste")
			(net "SMB_NIC5_R_SDA")
		)
		(pad "2" smd circle
			(at 0.40005 0 180)
			(size 0 0)
			(layers "F.Cu" "F.Mask" "F.Paste")
			(net "P1V2_AUX")
		)
	)
	(footprint ""
		(layer "F.Cu")
		(at 148.511514 -286.844232 -90)
		(property "Reference" "R4574"
			(at 0 0 270)
			(layer "F.SilkS")
			(hide yes)
			(effects
				(font
					(size 1.27 1.27)
				)
			)
		)
		(property "Value" ""
			(at 0 0 270)
			(layer "F.Fab")
			(effects
				(font
					(size 1.27 1.27)
				)
			)
		)
		(duplicate_pad_numbers_are_jumpers no)
		(fp_line
			(start -0.7874 0.4064)
			(end -0.7874 -0.4064)
			(stroke
				(width 0.1524)
				(type default)
			)
			(layer "F.SilkS")
		)
		(fp_line
			(start 0.7874 0.4064)
			(end -0.7874 0.4064)
			(stroke
				(width 0.1524)
				(type default)
			)
			(layer "F.SilkS")
		)
		(fp_line
			(start -0.7874 -0.4064)
			(end 0.7874 -0.4064)
			(stroke
				(width 0.1524)
				(type default)
			)
			(layer "F.SilkS")
		)
		(fp_line
			(start 0.7874 -0.4064)
			(end 0.7874 0.4064)
			(stroke
				(width 0.1524)
				(type default)
			)
			(layer "F.SilkS")
		)
		(fp_line
			(start -0.67945 0.3048)
			(end -0.67945 -0.305054)
			(stroke
				(width 0.1)
				(type default)
			)
			(layer "F.Fab")
		)
		(fp_line
			(start -0.12065 0.3048)
			(end -0.67945 0.3048)
			(stroke
				(width 0.1)
				(type default)
			)
			(layer "F.Fab")
		)
		(fp_line
			(start 0.120396 0.3048)
			(end 0.120396 0.2794)
			(stroke
				(width 0.1)
				(type default)
			)
			(layer "F.Fab")
		)
		(fp_line
			(start 0.67945 0.3048)
			(end 0.120396 0.3048)
			(stroke
				(width 0.1)
				(type default)
			)
			(layer "F.Fab")
		)
		(fp_line
			(start -0.12065 0.2794)
			(end -0.12065 0.3048)
			(stroke
				(width 0.1)
				(type default)
			)
			(layer "F.Fab")
		)
		(fp_line
			(start 0.120396 0.2794)
			(end -0.12065 0.2794)
			(stroke
				(width 0.1)
				(type default)
			)
			(layer "F.Fab")
		)
		(fp_line
			(start -0.12065 -0.2794)
			(end 0.12065 -0.2794)
			(stroke
				(width 0.1)
				(type default)
			)
			(layer "F.Fab")
		)
		(fp_line
			(start 0.12065 -0.2794)
			(end 0.12065 -0.3048)
			(stroke
				(width 0.1)
				(type default)
			)
			(layer "F.Fab")
		)
		(fp_line
			(start 0.12065 -0.3048)
			(end 0.67945 -0.3048)
			(stroke
				(width 0.1)
				(type default)
			)
			(layer "F.Fab")
		)
		(fp_line
			(start 0.67945 -0.3048)
			(end 0.67945 0.3048)
			(stroke
				(width 0.1)
				(type default)
			)
			(layer "F.Fab")
		)
		(fp_line
			(start -0.67945 -0.305054)
			(end -0.12065 -0.305054)
			(stroke
				(width 0.1)
				(type default)
			)
			(layer "F.Fab")
		)
		(fp_line
			(start -0.12065 -0.305054)
			(end -0.12065 -0.2794)
			(stroke
				(width 0.1)
				(type default)
			)
			(layer "F.Fab")
		)
		(pad "1" smd circle
			(at -0.40005 0 270)
			(size 0 0)
			(layers "F.Cu" "F.Mask" "F.Paste")
			(net "PCEPLL6_VDDA18_PEX1")
		)
		(pad "2" smd circle
			(at 0.40005 0 270)
			(size 0 0)
			(layers "F.Cu" "F.Mask" "F.Paste")
			(net "PCEPLL6_VDDA18_PEX1_R")
		)
	)
	(footprint ""
		(layer "F.Cu")
		(at 191.756538 -17.419574 180)
		(property "Reference" "R1674"
			(at 0 0 180)
			(layer "F.SilkS")
			(hide yes)
			(effects
				(font
					(size 1.27 1.27)
				)
			)
		)
		(property "Value" ""
			(at 0 0 180)
			(layer "F.Fab")
			(effects
				(font
					(size 1.27 1.27)
				)
			)
		)
		(duplicate_pad_numbers_are_jumpers no)
		(fp_line
			(start 0.7874 0.4064)
			(end -0.7874 0.4064)
			(stroke
				(width 0.1524)
				(type default)
			)
			(layer "F.SilkS")
		)
		(fp_line
			(start 0.7874 -0.4064)
			(end 0.7874 0.4064)
			(stroke
				(width 0.1524)
				(type default)
			)
			(layer "F.SilkS")
		)
		(fp_line
			(start -0.7874 0.4064)
			(end -0.7874 -0.4064)
			(stroke
				(width 0.1524)
				(type default)
			)
			(layer "F.SilkS")
		)
		(fp_line
			(start -0.7874 -0.4064)
			(end 0.7874 -0.4064)
			(stroke
				(width 0.1524)
				(type default)
			)
			(layer "F.SilkS")
		)
		(fp_line
			(start 0.67945 0.3048)
			(end 0.120396 0.3048)
			(stroke
				(width 0.1)
				(type default)
			)
			(layer "F.Fab")
		)
		(fp_line
			(start 0.67945 -0.3048)
			(end 0.67945 0.3048)
			(stroke
				(width 0.1)
				(type default)
			)
			(layer "F.Fab")
		)
		(fp_line
			(start 0.12065 -0.2794)
			(end 0.12065 -0.3048)
			(stroke
				(width 0.1)
				(type default)
			)
			(layer "F.Fab")
		)
		(fp_line
			(start 0.12065 -0.3048)
			(end 0.67945 -0.3048)
			(stroke
				(width 0.1)
				(type default)
			)
			(layer "F.Fab")
		)
		(fp_line
			(start 0.120396 0.3048)
			(end 0.120396 0.2794)
			(stroke
				(width 0.1)
				(type default)
			)
			(layer "F.Fab")
		)
		(fp_line
			(start 0.120396 0.2794)
			(end -0.12065 0.2794)
			(stroke
				(width 0.1)
				(type default)
			)
			(layer "F.Fab")
		)
		(fp_line
			(start -0.12065 0.3048)
			(end -0.67945 0.3048)
			(stroke
				(width 0.1)
				(type default)
			)
			(layer "F.Fab")
		)
		(fp_line
			(start -0.12065 0.2794)
			(end -0.12065 0.3048)
			(stroke
				(width 0.1)
				(type default)
			)
			(layer "F.Fab")
		)
		(fp_line
			(start -0.12065 -0.2794)
			(end 0.12065 -0.2794)
			(stroke
				(width 0.1)
				(type default)
			)
			(layer "F.Fab")
		)
		(fp_line
			(start -0.12065 -0.305054)
			(end -0.12065 -0.2794)
			(stroke
				(width 0.1)
				(type default)
			)
			(layer "F.Fab")
		)
		(fp_line
			(start -0.67945 0.3048)
			(end -0.67945 -0.305054)
			(stroke
				(width 0.1)
				(type default)
			)
			(layer "F.Fab")
		)
		(fp_line
			(start -0.67945 -0.305054)
			(end -0.12065 -0.305054)
			(stroke
				(width 0.1)
				(type default)
			)
			(layer "F.Fab")
		)
		(pad "1" smd circle
			(at -0.40005 0 180)
			(size 0 0)
			(layers "F.Cu" "F.Mask" "F.Paste")
			(net "P3V3_SSD6")
		)
		(pad "2" smd circle
			(at 0.40005 0 180)
			(size 0 0)
			(layers "F.Cu" "F.Mask" "F.Paste")
			(net "SMB_ISO_SSD6_SCL")
		)
	)
	(footprint ""
		(layer "F.Cu")
		(at 291.194998 -97.718372 180)
		(property "Reference" "R303"
			(at 0 0 180)
			(layer "F.SilkS")
			(hide yes)
			(effects
				(font
					(size 1.27 1.27)
				)
			)
		)
		(property "Value" ""
			(at 0 0 180)
			(layer "F.Fab")
			(effects
				(font
					(size 1.27 1.27)
				)
			)
		)
		(duplicate_pad_numbers_are_jumpers no)
		(fp_line
			(start 0.7874 0.4064)
			(end -0.7874 0.4064)
			(stroke
				(width 0.1524)
				(type default)
			)
			(layer "F.SilkS")
		)
		(fp_line
			(start 0.7874 -0.4064)
			(end 0.7874 0.4064)
			(stroke
				(width 0.1524)
				(type default)
			)
			(layer "F.SilkS")
		)
		(fp_line
			(start -0.7874 0.4064)
			(end -0.7874 -0.4064)
			(stroke
				(width 0.1524)
				(type default)
			)
			(layer "F.SilkS")
		)
		(fp_line
			(start -0.7874 -0.4064)
			(end 0.7874 -0.4064)
			(stroke
				(width 0.1524)
				(type default)
			)
			(layer "F.SilkS")
		)
		(fp_line
			(start 0.67945 0.3048)
			(end 0.120396 0.3048)
			(stroke
				(width 0.1)
				(type default)
			)
			(layer "F.Fab")
		)
		(fp_line
			(start 0.67945 -0.3048)
			(end 0.67945 0.3048)
			(stroke
				(width 0.1)
				(type default)
			)
			(layer "F.Fab")
		)
		(fp_line
			(start 0.12065 -0.2794)
			(end 0.12065 -0.3048)
			(stroke
				(width 0.1)
				(type default)
			)
			(layer "F.Fab")
		)
		(fp_line
			(start 0.12065 -0.3048)
			(end 0.67945 -0.3048)
			(stroke
				(width 0.1)
				(type default)
			)
			(layer "F.Fab")
		)
		(fp_line
			(start 0.120396 0.3048)
			(end 0.120396 0.2794)
			(stroke
				(width 0.1)
				(type default)
			)
			(layer "F.Fab")
		)
		(fp_line
			(start 0.120396 0.2794)
			(end -0.12065 0.2794)
			(stroke
				(width 0.1)
				(type default)
			)
			(layer "F.Fab")
		)
		(fp_line
			(start -0.12065 0.3048)
			(end -0.67945 0.3048)
			(stroke
				(width 0.1)
				(type default)
			)
			(layer "F.Fab")
		)
		(fp_line
			(start -0.12065 0.2794)
			(end -0.12065 0.3048)
			(stroke
				(width 0.1)
				(type default)
			)
			(layer "F.Fab")
		)
		(fp_line
			(start -0.12065 -0.2794)
			(end 0.12065 -0.2794)
			(stroke
				(width 0.1)
				(type default)
			)
			(layer "F.Fab")
		)
		(fp_line
			(start -0.12065 -0.305054)
			(end -0.12065 -0.2794)
			(stroke
				(width 0.1)
				(type default)
			)
			(layer "F.Fab")
		)
		(fp_line
			(start -0.67945 0.3048)
			(end -0.67945 -0.305054)
			(stroke
				(width 0.1)
				(type default)
			)
			(layer "F.Fab")
		)
		(fp_line
			(start -0.67945 -0.305054)
			(end -0.12065 -0.305054)
			(stroke
				(width 0.1)
				(type default)
			)
			(layer "F.Fab")
		)
		(pad "1" smd circle
			(at -0.40005 0 180)
			(size 0 0)
			(layers "F.Cu" "F.Mask" "F.Paste")
			(net "RST_NIC5_PERST3_R_N")
		)
		(pad "2" smd circle
			(at 0.40005 0 180)
			(size 0 0)
			(layers "F.Cu" "F.Mask" "F.Paste")
			(net "RST_HP_NIC5_BUF_N")
		)
	)
	(footprint ""
		(layer "F.Cu")
		(at 438.013348 -104.267508 -90)
		(property "Reference" "R767"
			(at 0 0 270)
			(layer "F.SilkS")
			(hide yes)
			(effects
				(font
					(size 1.27 1.27)
				)
			)
		)
		(property "Value" ""
			(at 0 0 270)
			(layer "F.Fab")
			(effects
				(font
					(size 1.27 1.27)
				)
			)
		)
		(duplicate_pad_numbers_are_jumpers no)
		(fp_line
			(start -0.7874 0.4064)
			(end -0.7874 -0.4064)
			(stroke
				(width 0.1524)
				(type default)
			)
			(layer "F.SilkS")
		)
		(fp_line
			(start 0.7874 0.4064)
			(end -0.7874 0.4064)
			(stroke
				(width 0.1524)
				(type default)
			)
			(layer "F.SilkS")
		)
		(fp_line
			(start -0.7874 -0.4064)
			(end 0.7874 -0.4064)
			(stroke
				(width 0.1524)
				(type default)
			)
			(layer "F.SilkS")
		)
		(fp_line
			(start 0.7874 -0.4064)
			(end 0.7874 0.4064)
			(stroke
				(width 0.1524)
				(type default)
			)
			(layer "F.SilkS")
		)
		(fp_line
			(start -0.67945 0.3048)
			(end -0.67945 -0.305054)
			(stroke
				(width 0.1)
				(type default)
			)
			(layer "F.Fab")
		)
		(fp_line
			(start -0.12065 0.3048)
			(end -0.67945 0.3048)
			(stroke
				(width 0.1)
				(type default)
			)
			(layer "F.Fab")
		)
		(fp_line
			(start 0.120396 0.3048)
			(end 0.120396 0.2794)
			(stroke
				(width 0.1)
				(type default)
			)
			(layer "F.Fab")
		)
		(fp_line
			(start 0.67945 0.3048)
			(end 0.120396 0.3048)
			(stroke
				(width 0.1)
				(type default)
			)
			(layer "F.Fab")
		)
		(fp_line
			(start -0.12065 0.2794)
			(end -0.12065 0.3048)
			(stroke
				(width 0.1)
				(type default)
			)
			(layer "F.Fab")
		)
		(fp_line
			(start 0.120396 0.2794)
			(end -0.12065 0.2794)
			(stroke
				(width 0.1)
				(type default)
			)
			(layer "F.Fab")
		)
		(fp_line
			(start -0.12065 -0.2794)
			(end 0.12065 -0.2794)
			(stroke
				(width 0.1)
				(type default)
			)
			(layer "F.Fab")
		)
		(fp_line
			(start 0.12065 -0.2794)
			(end 0.12065 -0.3048)
			(stroke
				(width 0.1)
				(type default)
			)
			(layer "F.Fab")
		)
		(fp_line
			(start 0.12065 -0.3048)
			(end 0.67945 -0.3048)
			(stroke
				(width 0.1)
				(type default)
			)
			(layer "F.Fab")
		)
		(fp_line
			(start 0.67945 -0.3048)
			(end 0.67945 0.3048)
			(stroke
				(width 0.1)
				(type default)
			)
			(layer "F.Fab")
		)
		(fp_line
			(start -0.67945 -0.305054)
			(end -0.12065 -0.305054)
			(stroke
				(width 0.1)
				(type default)
			)
			(layer "F.Fab")
		)
		(fp_line
			(start -0.12065 -0.305054)
			(end -0.12065 -0.2794)
			(stroke
				(width 0.1)
				(type default)
			)
			(layer "F.Fab")
		)
		(pad "1" smd circle
			(at -0.40005 0 270)
			(size 0 0)
			(layers "F.Cu" "F.Mask" "F.Paste")
			(net "P12V_NIC7")
		)
		(pad "2" smd circle
			(at 0.40005 0 270)
			(size 0 0)
			(layers "F.Cu" "F.Mask" "F.Paste")
			(net "P12V_NIC7_VIN_N")
		)
	)
	(footprint ""
		(layer "F.Cu")
		(at 271.480534 -124.605542)
		(property "Reference" "C463"
			(at 0 0 0)
			(layer "F.SilkS")
			(hide yes)
			(effects
				(font
					(size 1.27 1.27)
				)
			)
		)
		(property "Value" ""
			(at 0 0 0)
			(layer "F.Fab")
			(effects
				(font
					(size 1.27 1.27)
				)
			)
		)
		(duplicate_pad_numbers_are_jumpers no)
		(fp_line
			(start -0.299974 -0.150114)
			(end 0.299974 -0.150114)
			(stroke
				(width 0.1)
				(type default)
			)
			(layer "F.Fab")
		)
		(fp_line
			(start -0.299974 0.150114)
			(end -0.299974 -0.150114)
			(stroke
				(width 0.1)
				(type default)
			)
			(layer "F.Fab")
		)
		(fp_line
			(start 0.299974 -0.150114)
			(end 0.299974 0.150114)
			(stroke
				(width 0.1)
				(type default)
			)
			(layer "F.Fab")
		)
		(fp_line
			(start 0.299974 0.150114)
			(end -0.299974 0.150114)
			(stroke
				(width 0.1)
				(type default)
			)
			(layer "F.Fab")
		)
		(pad "1" smd rect
			(at -0.2667 0)
			(size 0.3048 0.381)
			(layers "F.Cu" "F.Mask" "F.Paste")
			(net "P5E_PEX2_STN1_TX_DN<27>")
		)
		(pad "2" smd rect
			(at 0.2667 0)
			(size 0.3048 0.381)
			(layers "F.Cu" "F.Mask" "F.Paste")
			(net "P5E_PEX2_STN1_TX_C_DN<27>")
		)
	)
)
